(kicad_pcb
	(version 20260206)
	(generator "pcbnew")
	(generator_version "10.0")
	(general
		(thickness 1.6)
		(legacy_teardrops no)
	)
	(paper "A4")
	(title_block
		(title "03242023_DA0F0TMBIJ0_F0T_Motherboard_J_brd_V01_OCP.brd")
		(comment 1 "Grand Teton / footprints 4484-4489 of 6105")
	)
	(layers
		(0 "F.Cu" signal "TOP")
		(4 "In1.Cu" signal "GND")
		(6 "In2.Cu" signal "IN1")
		(8 "In3.Cu" signal "GND1")
		(10 "In4.Cu" signal "IN2")
		(12 "In5.Cu" signal "GND2")
		(14 "In6.Cu" signal "IN3")
		(16 "In7.Cu" signal "GND3")
		(18 "In8.Cu" signal "VCC")
		(20 "In9.Cu" signal "VCC1")
		(22 "In10.Cu" signal "GND4")
		(24 "In11.Cu" signal "IN4")
		(26 "In12.Cu" signal "GND5")
		(28 "In13.Cu" signal "IN5")
		(30 "In14.Cu" signal "GND6")
		(32 "In15.Cu" signal "IN6")
		(34 "In16.Cu" signal "GND7")
		(2 "B.Cu" signal "BOTTOM")
		(9 "F.Adhes" user "F.Adhesive")
		(11 "B.Adhes" user "B.Adhesive")
		(13 "F.Paste" user "Package Geometry/Pastemask Top")
		(15 "B.Paste" user "Package Geometry/Pastemask Bottom")
		(5 "F.SilkS" user "Ref Des/Silkscreen Top")
		(7 "B.SilkS" user "Ref Des/Silkscreen Bottom")
		(1 "F.Mask" user "Board Geometry/Soldermask Top")
		(3 "B.Mask" user "Board Geometry/Soldermask Bottom")
		(17 "Dwgs.User" user "User.Drawings")
		(19 "Cmts.User" user "User.Comments")
		(21 "Eco1.User" user "User.Eco1")
		(23 "Eco2.User" user "User.Eco2")
		(25 "Edge.Cuts" user "Board Geometry/Outline")
		(27 "Margin" user)
		(31 "F.CrtYd" user "Package Geometry/Place Bound Top")
		(29 "B.CrtYd" user "Package Geometry/Place Bound Bottom")
		(35 "F.Fab" user "Ref Des/Assembly Top")
		(33 "B.Fab" user "Ref Des/Assembly Bottom")
	)
	(footprint ""
		(layer "B.Cu")
		(at 339.298534 8.003794 180)
		(property "Reference" "J114"
			(at 4.172204 -1.648206 270)
			(unlocked yes)
			(layer "B.SilkS")
			(effects
				(font
					(size 0.7874 0.5842)
					(thickness 0.1524)
				)
				(justify left mirror)
			)
		)
		(property "Value" ""
			(at 0 0 0)
			(layer "B.Fab")
			(effects
				(font
					(size 1.27 1.27)
				)
				(justify mirror)
			)
		)
		(duplicate_pad_numbers_are_jumpers no)
		(fp_line
			(start 1.2192 2.1082)
			(end 1.2192 -2.1082)
			(stroke
				(width 0.1524)
				(type default)
			)
			(layer "B.SilkS")
		)
		(fp_line
			(start 1.2192 -2.1082)
			(end -1.2192 -2.1082)
			(stroke
				(width 0.1524)
				(type default)
			)
			(layer "B.SilkS")
		)
		(fp_line
			(start -1.2192 2.1082)
			(end 1.2192 2.1082)
			(stroke
				(width 0.1524)
				(type default)
			)
			(layer "B.SilkS")
		)
		(fp_line
			(start -1.2192 -2.1082)
			(end -1.2192 2.1082)
			(stroke
				(width 0.1524)
				(type default)
			)
			(layer "B.SilkS")
		)
		(pad "" np_thru_hole circle
			(at -3.4671 -1.27 90)
			(size 1.0414 1.0414)
			(drill 1.0414)
			(layers "*.Cu" "*.Mask")
			(clearance 0.381)
			(thermal_gap 0.381)
		)
		(pad "" np_thru_hole circle
			(at -3.4671 1.27 90)
			(size 1.0414 1.0414)
			(drill 1.0414)
			(layers "*.Cu" "*.Mask")
			(clearance 0.381)
			(thermal_gap 0.381)
		)
		(pad "" np_thru_hole circle
			(at 2.8829 -1.27 90)
			(size 1.0414 1.0414)
			(drill 1.0414)
			(layers "*.Cu" "*.Mask")
			(clearance 0.381)
			(thermal_gap 0.381)
		)
		(pad "" np_thru_hole circle
			(at 2.8829 1.27 90)
			(size 1.0414 1.0414)
			(drill 1.0414)
			(layers "*.Cu" "*.Mask")
			(clearance 0.381)
			(thermal_gap 0.381)
		)
		(pad "1" smd rect
			(at -0.8255 -0.249936 90)
			(size 0.3048 0.508)
			(layers "B.Cu" "B.Mask" "B.Paste")
			(net "DELTA_L_85_5INCH_IN5_DP")
		)
		(pad "2" smd rect
			(at -0.8255 0.249936 90)
			(size 0.3048 0.508)
			(layers "B.Cu" "B.Mask" "B.Paste")
			(net "DELTA_L_85_5INCH_IN5_DN")
		)
		(pad "3" smd circle
			(at 0 0)
			(size 0 0)
			(layers "B.Cu" "B.Mask" "B.Paste")
			(net "DELTA_L_GND_1")
		)
		(zone
			(layers "F.Cu" "B.Cu" "In1.Cu" "In2.Cu" "In3.Cu" "In4.Cu" "In5.Cu" "In6.Cu"
				"In7.Cu" "In8.Cu" "In9.Cu" "In10.Cu" "In11.Cu" "In12.Cu" "In13.Cu" "In14.Cu"
				"In15.Cu" "In16.Cu"
			)
			(hatch none 0.5)
			(connect_pads
				(clearance 0)
			)
			(min_thickness 0.25)
			(keepout
				(tracks not_allowed)
				(vias allowed)
				(pads allowed)
				(copperpour not_allowed)
				(footprints allowed)
			)
			(placement
				(enabled no)
				(sheetname "")
			)
			(fill
				(thermal_gap 0.5)
				(thermal_bridge_width 0.5)
				(island_removal_mode 0)
			)
			(polygon
				(pts
					(arc
						(start 337.342734 6.733794)
						(mid 335.488534 6.733794)
						(end 337.342734 6.733794)
					)
				)
			)
		)
		(zone
			(layers "F.Cu" "B.Cu" "In1.Cu" "In2.Cu" "In3.Cu" "In4.Cu" "In5.Cu" "In6.Cu"
				"In7.Cu" "In8.Cu" "In9.Cu" "In10.Cu" "In11.Cu" "In12.Cu" "In13.Cu" "In14.Cu"
				"In15.Cu" "In16.Cu"
			)
			(hatch none 0.5)
			(connect_pads
				(clearance 0)
			)
			(min_thickness 0.25)
			(keepout
				(tracks not_allowed)
				(vias allowed)
				(pads allowed)
				(copperpour not_allowed)
				(footprints allowed)
			)
			(placement
				(enabled no)
				(sheetname "")
			)
			(fill
				(thermal_gap 0.5)
				(thermal_bridge_width 0.5)
				(island_removal_mode 0)
			)
			(polygon
				(pts
					(arc
						(start 337.342734 9.273794)
						(mid 335.488534 9.273794)
						(end 337.342734 9.273794)
					)
				)
			)
		)
		(zone
			(layers "F.Cu" "B.Cu" "In1.Cu" "In2.Cu" "In3.Cu" "In4.Cu" "In5.Cu" "In6.Cu"
				"In7.Cu" "In8.Cu" "In9.Cu" "In10.Cu" "In11.Cu" "In12.Cu" "In13.Cu" "In14.Cu"
				"In15.Cu" "In16.Cu"
			)
			(hatch none 0.5)
			(connect_pads
				(clearance 0)
			)
			(min_thickness 0.25)
			(keepout
				(tracks not_allowed)
				(vias allowed)
				(pads allowed)
				(copperpour not_allowed)
				(footprints allowed)
			)
			(placement
				(enabled no)
				(sheetname "")
			)
			(fill
				(thermal_gap 0.5)
				(thermal_bridge_width 0.5)
				(island_removal_mode 0)
			)
			(polygon
				(pts
					(arc
						(start 343.692734 6.733794)
						(mid 341.838534 6.733794)
						(end 343.692734 6.733794)
					)
				)
			)
		)
		(zone
			(layers "F.Cu" "B.Cu" "In1.Cu" "In2.Cu" "In3.Cu" "In4.Cu" "In5.Cu" "In6.Cu"
				"In7.Cu" "In8.Cu" "In9.Cu" "In10.Cu" "In11.Cu" "In12.Cu" "In13.Cu" "In14.Cu"
				"In15.Cu" "In16.Cu"
			)
			(hatch none 0.5)
			(connect_pads
				(clearance 0)
			)
			(min_thickness 0.25)
			(keepout
				(tracks not_allowed)
				(vias allowed)
				(pads allowed)
				(copperpour not_allowed)
				(footprints allowed)
			)
			(placement
				(enabled no)
				(sheetname "")
			)
			(fill
				(thermal_gap 0.5)
				(thermal_bridge_width 0.5)
				(island_removal_mode 0)
			)
			(polygon
				(pts
					(arc
						(start 343.692734 9.273794)
						(mid 341.838534 9.273794)
						(end 343.692734 9.273794)
					)
				)
			)
		)
		(zone
			(layer "B.Cu")
			(hatch none 0.5)
			(connect_pads
				(clearance 0)
			)
			(min_thickness 0.25)
			(keepout
				(tracks not_allowed)
				(vias allowed)
				(pads allowed)
				(copperpour not_allowed)
				(footprints allowed)
			)
			(placement
				(enabled no)
				(sheetname "")
			)
			(fill
				(thermal_gap 0.5)
				(thermal_bridge_width 0.5)
				(island_removal_mode 0)
			)
			(polygon
				(pts
					(xy 340.416134 8.552434) (xy 340.416134 8.45693) (xy 339.819234 8.45693) (xy 339.819234 8.05053)
					(xy 340.416134 8.05053) (xy 340.416134 7.957058) (xy 339.819234 7.957058) (xy 339.819234 7.550658)
					(xy 340.416134 7.550658) (xy 340.416134 7.455154) (xy 339.717634 7.455154) (xy 339.717634 8.552434)
				)
			)
		)
	)
	(footprint ""
		(layer "B.Cu")
		(at 30.155896 -127.416052 180)
		(property "Reference" "PR276"
			(at 0 0 0)
			(layer "B.SilkS")
			(hide yes)
			(effects
				(font
					(size 1.27 1.27)
				)
				(justify mirror)
			)
		)
		(property "Value" ""
			(at 0 0 0)
			(layer "B.Fab")
			(effects
				(font
					(size 1.27 1.27)
				)
				(justify mirror)
			)
		)
		(duplicate_pad_numbers_are_jumpers no)
		(fp_line
			(start 0.7874 0.4064)
			(end 0.7874 -0.4064)
			(stroke
				(width 0.1524)
				(type default)
			)
			(layer "B.SilkS")
		)
		(fp_line
			(start 0.7874 -0.4064)
			(end -0.7874 -0.4064)
			(stroke
				(width 0.1524)
				(type default)
			)
			(layer "B.SilkS")
		)
		(fp_line
			(start -0.7874 0.4064)
			(end 0.7874 0.4064)
			(stroke
				(width 0.1524)
				(type default)
			)
			(layer "B.SilkS")
		)
		(fp_line
			(start -0.7874 -0.4064)
			(end -0.7874 0.4064)
			(stroke
				(width 0.1524)
				(type default)
			)
			(layer "B.SilkS")
		)
		(fp_line
			(start 0.67945 0.3048)
			(end 0.67945 -0.305054)
			(stroke
				(width 0.1)
				(type default)
			)
			(layer "B.Fab")
		)
		(fp_line
			(start 0.67945 -0.305054)
			(end 0.12065 -0.305054)
			(stroke
				(width 0.1)
				(type default)
			)
			(layer "B.Fab")
		)
		(fp_line
			(start 0.12065 0.3048)
			(end 0.67945 0.3048)
			(stroke
				(width 0.1)
				(type default)
			)
			(layer "B.Fab")
		)
		(fp_line
			(start 0.12065 0.2794)
			(end 0.12065 0.3048)
			(stroke
				(width 0.1)
				(type default)
			)
			(layer "B.Fab")
		)
		(fp_line
			(start 0.12065 -0.2794)
			(end -0.12065 -0.2794)
			(stroke
				(width 0.1)
				(type default)
			)
			(layer "B.Fab")
		)
		(fp_line
			(start 0.12065 -0.305054)
			(end 0.12065 -0.2794)
			(stroke
				(width 0.1)
				(type default)
			)
			(layer "B.Fab")
		)
		(fp_line
			(start -0.120396 0.3048)
			(end -0.120396 0.2794)
			(stroke
				(width 0.1)
				(type default)
			)
			(layer "B.Fab")
		)
		(fp_line
			(start -0.120396 0.2794)
			(end 0.12065 0.2794)
			(stroke
				(width 0.1)
				(type default)
			)
			(layer "B.Fab")
		)
		(fp_line
			(start -0.12065 -0.2794)
			(end -0.12065 -0.3048)
			(stroke
				(width 0.1)
				(type default)
			)
			(layer "B.Fab")
		)
		(fp_line
			(start -0.12065 -0.3048)
			(end -0.67945 -0.3048)
			(stroke
				(width 0.1)
				(type default)
			)
			(layer "B.Fab")
		)
		(fp_line
			(start -0.67945 0.3048)
			(end -0.120396 0.3048)
			(stroke
				(width 0.1)
				(type default)
			)
			(layer "B.Fab")
		)
		(fp_line
			(start -0.67945 -0.3048)
			(end -0.67945 0.3048)
			(stroke
				(width 0.1)
				(type default)
			)
			(layer "B.Fab")
		)
		(pad "1" smd circle
			(at 0.40005 0)
			(size 0 0)
			(layers "B.Cu" "B.Mask" "B.Paste")
			(net "PVCCINFAON_CPU1_VIN_CSNIN")
		)
		(pad "2" smd circle
			(at -0.40005 0)
			(size 0 0)
			(layers "B.Cu" "B.Mask" "B.Paste")
			(net "GND")
		)
	)
	(footprint ""
		(layer "B.Cu")
		(at 105.679494 -248.49836 -90)
		(property "Reference" "C336"
			(at 0 0 90)
			(layer "B.SilkS")
			(hide yes)
			(effects
				(font
					(size 1.27 1.27)
				)
				(justify mirror)
			)
		)
		(property "Value" ""
			(at 0 0 90)
			(layer "B.Fab")
			(effects
				(font
					(size 1.27 1.27)
				)
				(justify mirror)
			)
		)
		(duplicate_pad_numbers_are_jumpers no)
		(fp_line
			(start -1.524 0.762)
			(end 1.524 0.762)
			(stroke
				(width 0.1524)
				(type default)
			)
			(layer "B.SilkS")
		)
		(fp_line
			(start 1.524 0.762)
			(end 1.524 -0.762)
			(stroke
				(width 0.1524)
				(type default)
			)
			(layer "B.SilkS")
		)
		(fp_line
			(start -1.524 -0.762)
			(end -1.524 0.762)
			(stroke
				(width 0.1524)
				(type default)
			)
			(layer "B.SilkS")
		)
		(fp_line
			(start 1.524 -0.762)
			(end -1.524 -0.762)
			(stroke
				(width 0.1524)
				(type default)
			)
			(layer "B.SilkS")
		)
		(fp_line
			(start -1.1049 0.724916)
			(end -1.1049 -0.724916)
			(stroke
				(width 0.1)
				(type default)
			)
			(layer "B.Fab")
		)
		(fp_line
			(start 1.1049 0.724916)
			(end -1.1049 0.724916)
			(stroke
				(width 0.1)
				(type default)
			)
			(layer "B.Fab")
		)
		(fp_line
			(start -1.1049 -0.724916)
			(end 1.1049 -0.724916)
			(stroke
				(width 0.1)
				(type default)
			)
			(layer "B.Fab")
		)
		(fp_line
			(start 1.1049 -0.724916)
			(end 1.1049 0.724916)
			(stroke
				(width 0.1)
				(type default)
			)
			(layer "B.Fab")
		)
		(pad "1" smd rect
			(at 0.889 0 270)
			(size 1.016 1.27)
			(layers "B.Cu" "B.Mask" "B.Paste")
			(net "PVCCIN_CPU1")
		)
		(pad "2" smd rect
			(at -0.889 0 270)
			(size 1.016 1.27)
			(layers "B.Cu" "B.Mask" "B.Paste")
			(net "GND")
		)
	)
	(footprint ""
		(layer "B.Cu")
		(at 161.29 -15.712948 -90)
		(property "Reference" "R1385"
			(at 0 0 90)
			(layer "B.SilkS")
			(hide yes)
			(effects
				(font
					(size 1.27 1.27)
				)
				(justify mirror)
			)
		)
		(property "Value" ""
			(at 0 0 90)
			(layer "B.Fab")
			(effects
				(font
					(size 1.27 1.27)
				)
				(justify mirror)
			)
		)
		(duplicate_pad_numbers_are_jumpers no)
		(fp_line
			(start -0.7874 0.4064)
			(end 0.7874 0.4064)
			(stroke
				(width 0.1524)
				(type default)
			)
			(layer "B.SilkS")
		)
		(fp_line
			(start 0.7874 0.4064)
			(end 0.7874 -0.4064)
			(stroke
				(width 0.1524)
				(type default)
			)
			(layer "B.SilkS")
		)
		(fp_line
			(start -0.7874 -0.4064)
			(end -0.7874 0.4064)
			(stroke
				(width 0.1524)
				(type default)
			)
			(layer "B.SilkS")
		)
		(fp_line
			(start 0.7874 -0.4064)
			(end -0.7874 -0.4064)
			(stroke
				(width 0.1524)
				(type default)
			)
			(layer "B.SilkS")
		)
		(fp_line
			(start -0.67945 0.3048)
			(end -0.120396 0.3048)
			(stroke
				(width 0.1)
				(type default)
			)
			(layer "B.Fab")
		)
		(fp_line
			(start -0.120396 0.3048)
			(end -0.120396 0.2794)
			(stroke
				(width 0.1)
				(type default)
			)
			(layer "B.Fab")
		)
		(fp_line
			(start 0.12065 0.3048)
			(end 0.67945 0.3048)
			(stroke
				(width 0.1)
				(type default)
			)
			(layer "B.Fab")
		)
		(fp_line
			(start 0.67945 0.3048)
			(end 0.67945 -0.305054)
			(stroke
				(width 0.1)
				(type default)
			)
			(layer "B.Fab")
		)
		(fp_line
			(start -0.120396 0.2794)
			(end 0.12065 0.2794)
			(stroke
				(width 0.1)
				(type default)
			)
			(layer "B.Fab")
		)
		(fp_line
			(start 0.12065 0.2794)
			(end 0.12065 0.3048)
			(stroke
				(width 0.1)
				(type default)
			)
			(layer "B.Fab")
		)
		(fp_line
			(start -0.12065 -0.2794)
			(end -0.12065 -0.3048)
			(stroke
				(width 0.1)
				(type default)
			)
			(layer "B.Fab")
		)
		(fp_line
			(start 0.12065 -0.2794)
			(end -0.12065 -0.2794)
			(stroke
				(width 0.1)
				(type default)
			)
			(layer "B.Fab")
		)
		(fp_line
			(start -0.67945 -0.3048)
			(end -0.67945 0.3048)
			(stroke
				(width 0.1)
				(type default)
			)
			(layer "B.Fab")
		)
		(fp_line
			(start -0.12065 -0.3048)
			(end -0.67945 -0.3048)
			(stroke
				(width 0.1)
				(type default)
			)
			(layer "B.Fab")
		)
		(fp_line
			(start 0.12065 -0.305054)
			(end 0.12065 -0.2794)
			(stroke
				(width 0.1)
				(type default)
			)
			(layer "B.Fab")
		)
		(fp_line
			(start 0.67945 -0.305054)
			(end 0.12065 -0.305054)
			(stroke
				(width 0.1)
				(type default)
			)
			(layer "B.Fab")
		)
		(pad "1" smd circle
			(at 0.40005 0 90)
			(size 0 0)
			(layers "B.Cu" "B.Mask" "B.Paste")
			(net "SMB_SML0_3V3AUX_SDA")
		)
		(pad "2" smd circle
			(at -0.40005 0 90)
			(size 0 0)
			(layers "B.Cu" "B.Mask" "B.Paste")
			(net "P3V3_AUX")
		)
	)
	(footprint ""
		(layer "B.Cu")
		(at 353.619308 -244.820186 -90)
		(property "Reference" "C391"
			(at 0 0 90)
			(layer "B.SilkS")
			(hide yes)
			(effects
				(font
					(size 1.27 1.27)
				)
				(justify mirror)
			)
		)
		(property "Value" ""
			(at 0 0 90)
			(layer "B.Fab")
			(effects
				(font
					(size 1.27 1.27)
				)
				(justify mirror)
			)
		)
		(duplicate_pad_numbers_are_jumpers no)
		(fp_line
			(start -1.524 0.762)
			(end 1.524 0.762)
			(stroke
				(width 0.1524)
				(type default)
			)
			(layer "B.SilkS")
		)
		(fp_line
			(start 1.524 0.762)
			(end 1.524 -0.762)
			(stroke
				(width 0.1524)
				(type default)
			)
			(layer "B.SilkS")
		)
		(fp_line
			(start -1.524 -0.762)
			(end -1.524 0.762)
			(stroke
				(width 0.1524)
				(type default)
			)
			(layer "B.SilkS")
		)
		(fp_line
			(start 1.524 -0.762)
			(end -1.524 -0.762)
			(stroke
				(width 0.1524)
				(type default)
			)
			(layer "B.SilkS")
		)
		(fp_line
			(start -1.1049 0.724916)
			(end -1.1049 -0.724916)
			(stroke
				(width 0.1)
				(type default)
			)
			(layer "B.Fab")
		)
		(fp_line
			(start 1.1049 0.724916)
			(end -1.1049 0.724916)
			(stroke
				(width 0.1)
				(type default)
			)
			(layer "B.Fab")
		)
		(fp_line
			(start -1.1049 -0.724916)
			(end 1.1049 -0.724916)
			(stroke
				(width 0.1)
				(type default)
			)
			(layer "B.Fab")
		)
		(fp_line
			(start 1.1049 -0.724916)
			(end 1.1049 0.724916)
			(stroke
				(width 0.1)
				(type default)
			)
			(layer "B.Fab")
		)
		(pad "1" smd rect
			(at 0.889 0 270)
			(size 1.016 1.27)
			(layers "B.Cu" "B.Mask" "B.Paste")
			(net "PVCCIN_CPU0")
		)
		(pad "2" smd rect
			(at -0.889 0 270)
			(size 1.016 1.27)
			(layers "B.Cu" "B.Mask" "B.Paste")
			(net "GND")
		)
	)
	(footprint ""
		(layer "B.Cu")
		(at 362.31449 -360.418126 -90)
		(property "Reference" "PR157"
			(at 0 0 90)
			(layer "B.SilkS")
			(hide yes)
			(effects
				(font
					(size 1.27 1.27)
				)
				(justify mirror)
			)
		)
		(property "Value" ""
			(at 0 0 90)
			(layer "B.Fab")
			(effects
				(font
					(size 1.27 1.27)
				)
				(justify mirror)
			)
		)
		(duplicate_pad_numbers_are_jumpers no)
		(fp_line
			(start -0.7874 0.4064)
			(end 0.7874 0.4064)
			(stroke
				(width 0.1524)
				(type default)
			)
			(layer "B.SilkS")
		)
		(fp_line
			(start 0.7874 0.4064)
			(end 0.7874 -0.4064)
			(stroke
				(width 0.1524)
				(type default)
			)
			(layer "B.SilkS")
		)
		(fp_line
			(start -0.7874 -0.4064)
			(end -0.7874 0.4064)
			(stroke
				(width 0.1524)
				(type default)
			)
			(layer "B.SilkS")
		)
		(fp_line
			(start 0.7874 -0.4064)
			(end -0.7874 -0.4064)
			(stroke
				(width 0.1524)
				(type default)
			)
			(layer "B.SilkS")
		)
		(fp_line
			(start -0.67945 0.3048)
			(end -0.120396 0.3048)
			(stroke
				(width 0.1)
				(type default)
			)
			(layer "B.Fab")
		)
		(fp_line
			(start -0.120396 0.3048)
			(end -0.120396 0.2794)
			(stroke
				(width 0.1)
				(type default)
			)
			(layer "B.Fab")
		)
		(fp_line
			(start 0.12065 0.3048)
			(end 0.67945 0.3048)
			(stroke
				(width 0.1)
				(type default)
			)
			(layer "B.Fab")
		)
		(fp_line
			(start 0.67945 0.3048)
			(end 0.67945 -0.305054)
			(stroke
				(width 0.1)
				(type default)
			)
			(layer "B.Fab")
		)
		(fp_line
			(start -0.120396 0.2794)
			(end 0.12065 0.2794)
			(stroke
				(width 0.1)
				(type default)
			)
			(layer "B.Fab")
		)
		(fp_line
			(start 0.12065 0.2794)
			(end 0.12065 0.3048)
			(stroke
				(width 0.1)
				(type default)
			)
			(layer "B.Fab")
		)
		(fp_line
			(start -0.12065 -0.2794)
			(end -0.12065 -0.3048)
			(stroke
				(width 0.1)
				(type default)
			)
			(layer "B.Fab")
		)
		(fp_line
			(start 0.12065 -0.2794)
			(end -0.12065 -0.2794)
			(stroke
				(width 0.1)
				(type default)
			)
			(layer "B.Fab")
		)
		(fp_line
			(start -0.67945 -0.3048)
			(end -0.67945 0.3048)
			(stroke
				(width 0.1)
				(type default)
			)
			(layer "B.Fab")
		)
		(fp_line
			(start -0.12065 -0.3048)
			(end -0.67945 -0.3048)
			(stroke
				(width 0.1)
				(type default)
			)
			(layer "B.Fab")
		)
		(fp_line
			(start 0.12065 -0.305054)
			(end 0.12065 -0.2794)
			(stroke
				(width 0.1)
				(type default)
			)
			(layer "B.Fab")
		)
		(fp_line
			(start 0.67945 -0.305054)
			(end 0.12065 -0.305054)
			(stroke
				(width 0.1)
				(type default)
			)
			(layer "B.Fab")
		)
		(pad "1" smd circle
			(at 0.40005 0 90)
			(size 0 0)
			(layers "B.Cu" "B.Mask" "B.Paste")
			(net "P12V_AUX")
		)
		(pad "2" smd circle
			(at -0.40005 0 90)
			(size 0 0)
			(layers "B.Cu" "B.Mask" "B.Paste")
			(net "PVCCIN_CPU0_CSPIN")
		)
	)
)
